# HONEY BADGER PANTHER+ BOARD HS(D)-1B BOM of 55.B0701.D21G_20150213.xlsx — HONEY BADGER PANTHER+ BOARD HS( (bom)
| Level | Parent Number | Part Number | Description | Green Factor | Life Cycle State | Manufacturer | Manufacturer Part Number | Source | BOM Usage | M/P Code | S/D | Qty | UoM | Location |
| 1 | 55.B0701.D21G | 086.0002Y.0824 | SCRW WAFRE M2.0 TAP L3.8 | R2_C; | Released | TBD |  | Single |  | Purchase | DIP | 2 | PCS |  |
| 1 | 55.B0701.D21G | 086.0004K.0328 | SCRW WAFRE M2L8 NI | R2_C; | Released | TBD |  | Single |  | Purchase | DIP | 2 | PCS |  |
| 1 | 55.B0701.D21G | 087.14203.0214 | NUT M2X1.4 PC | R2_C; | Released | TBD |  | Single |  | Purchase | DIP | 2 | PCS |  |
| 1 | 55.B0701.D21G | 34.B0704.001 | HSINK_60X48X13.5_CLIP_PAD_HB | R2_SA; | Released | CCI | Void | Single |  | Purchase | DIP | 1 | PCS | U13 |
| 1 | 55.B0701.D21G | 42.B0721.001 | HDLR M SATA HB GREEN | R2_C; | Released | TBD |  | Single |  | Purchase | DIP | 1 | PCS |  |
| 1 | 55.B0701.D21G | 42.B0722.001 | HDLR NGFF HB GREEN | R2_C; | Released | TBD |  | Single |  | Purchase | DIP | 1 | PCS |  |
| 1 | 55.B0701.D21G | 42.B0723.001 | HDLR GRIP PANTHER HB PVT | R2_C; | Released | TBD |  | Single |  | Purchase | DIP | 1 | PCS |  |
| 1 | 55.B0701.D21G | 55.B0701.S21G | HONEY BADGER PANTHER+ BOARD HS(S)-1B | N/A; | Released |  |  |  | E | Manufacture | DIP | 1 | PCS |  |
| 2 | 55.B0701.S21G | 025.60003.0011 | ANCHOR 1R2P 21U-91-03TB22 ,NY9T | R2_SA; | Released | PINREX | 21U-91-03TB22 | Single |  | Purchase | SMT | 2 | PCS | CN1 CN2 |
| 2 | 55.B0701.S21G | 062.10011.0791 | SKT DDR3 SO DIMM 204P ASAA627-JERB0-7H | R2_SA; | Released | FOXCONN | ASAA627-JERB0-7H | Single |  | Purchase | SMT | 2 | PCS | DIMM1 DIMM3 |
| 2 | 55.B0701.S21G | 062.10011.0801 | SKT DDR3 SO DIMM 204P ASAA627-JESB0-7H | R2_SA; | Released | FOXCONN | ASAA627-JESB0-7H | Single |  | Purchase | SMT | 2 | PCS | DIMM2 DIMM4 |
| 2 | 55.B0701.S21G | 071.46228.000G | IC FPGA EP4CE6E22C8N EQFP 144P | R2_SA; | Released | ALTERA | EP4CE6E22C8N | Single |  | Purchase | SMT | 1 | PCS | U14 |
| 2 | 55.B0701.S21G | 071.94420.0003 | IC CLK 9VRS4420DKLFT VFQFPN 48P | R2_SA; | Released | IDT | 9VRS4420DKLFT | Single |  | Purchase | SMT | 1 | PCS | U16 |
| 2 | 55.B0701.S21G | 071.AVOTO.0C0U | IC CPU AVOTON C2750 2.4 GHZ 8C BGA B-0 | R2_SA; | Released | INTEL | 930444 FH8065401488906 SR1CS | Single |  | Purchase | SMT | 1 | PCS | U13 |
| 2 | 55.B0701.S21G | 078.47422.05F1 | CHIP CAP C 0.47U 25V K0402 X5R | R2_SA;HF_SA;G_SA; | Released | TAIYO;DARFON;MURATA;TDK;YAGEO | TMK105ABJ474KV-F;C1005X5R474KFT;GRM155R61E474KA12D;C1005X5R1E474KT;CC0402KRX5R8BB474 | Multiple |  | Purchase | SMT | 3 | PCS | C113 C17 C19 |
| 2 | 55.B0701.S21G | 078.47522.0211 | CHIP CAP C 4.7U 25V K0805 X7R | R2_SA;HF_SA;G_SA; | Released | WALSIN;SAMSUNG;MURATA | 0805B475K250CT;CL21B475KAFNNNE;GRM21BR71E475KA73L | Multiple |  | Purchase | SMT | 3 | PCS | PC159 PC188 PC90 |
| 2 | 55.B0701.S21G | 078.56222.02FS | CHIP CAP C 5600P 25V K0402 X7R | R2_SA;HF_SA;G_SA; | Released | TDK;MURATA;TAIYO | C1005X7R1E562KT000F;GRM155R71E562KA01D;TMK105B7562KV-F | Multiple |  | Purchase | SMT | 1 | PCS | PC5 |
| 2 | 55.B0701.S21G | 082.20014.0001 | OSC 5MHZ 25PPM 15PF 3.3V HXO-SC SMD | R2_SA; | Released | HOSONIC | DSCA5.00000NNS | Single |  | Purchase | SMT | 1 | PCS | OSC1 |
| 2 | 55.B0701.S21G | 20.F0441.060 | CONN SMD 60P BSH-030-01-L-D-A-TR ,LCP | R2_SA;HF_SA; | Released | SAMTEC | BSH-030-01-L-D-A-TR | Single |  | Purchase | SMT | 1 | PCS | CN4 |
| 2 | 55.B0701.S21G | 21.61881.205 | HEAD ML 2R10P HC3105F ,PA6T | R2_SA; | Released | FOXCONN | HC3105F | Single |  | Purchase | SMT | 1 | PCS | CN3 |
| 2 | 55.B0701.S21G | 48.B0730.01B | PCB 13130-1B HONEY BADGER PNTHR MB 12L H | R2_C; | Released | HANNSTAR |  | Single |  | Purchase | SMT | 1 | PCS |  |
| 2 | 55.B0701.S21G | 62.10043.B01 | SKT MINI PCI 52P 80003-3021 H=5.7MM SMD | R2_SA; | Released | BELLWETHER | 80003-3021 | Single |  | Purchase | SMT | 1 | PCS | CN5 |
| 2 | 55.B0701.S21G | 62.10043.S61 | SKT MINI PCIE/SATA KEY:M 67P 80159-4224 | R2_SA;HF_SA; | Released | BELLWETHER | 80159-4224 | Single |  | Purchase | SMT | 1 | PCS | NGFF1 |
| 2 | 55.B0701.S21G | 62.10089.091 | SKT SPI CONN 8P G6179T010-001 SMD | R2_SA; | Released | WIESON | G6179T010-001 | Single |  | Purchase | SMT | 1 | PCS | SKT1 |
| 2 | 55.B0701.S21G | 63.00000.00L | CHIP RES 0 J 1/10W 0603 | R2_SA;HF_SA;G_SA; | Released | TA-I ; RALEC ; YAGEO ; WALSIN | RM06JTN0 ; RTT03000JTP ; RC0603JR-070RL ; WR06X000PTL | Multiple |  | Purchase | SMT | 11 | PCS | PR109 PR114 PR13 PR170 PR25 PR54 PR58 PR80 PR97 R271 R273 |
| 2 | 55.B0701.S21G | 63.10233.15L | CHIP RES 1K J 1/10W 0603 | R2_SA;HF_SA;G_SA; | Released | TA-I ; RALEC ; YAGEO | RM06JTN102 ; RTT03102JTP ; RC0603JR-071KL | Multiple |  | Purchase | SMT | 1 | PCS | R272 |
| 2 | 55.B0701.S21G | 63.15134.1DL | CHIP RES 150 J 1/16W 0402 | R2_SA;HF_SA;G_SA; | Released | TA-I ; RALEC ; CYNTEC ; YAGEO | RM04JTN151 ; RTT02151JTH ; RR0510S-151-JN ; RC0402JR-07150RL | Multiple |  | Purchase | SMT | 2 | PCS | R20 R96 |
| 2 | 55.B0701.S21G | 63.15334.1DL | CHIP RES 15K J 1/16W 0402 | R2_SA;HF_SA;G_SA; | Released | TA-I;RALEC;CYNTEC;YAGEO;WALSIN | RM04JTN153 ; RTT02153JTH ; RR0510S-153-JN ; RC0402JR-0715KL;WR04X153JTL | Multiple |  | Purchase | SMT | 1 | PCS | PR150 |
| 2 | 55.B0701.S21G | 63.22534.1DL | CHIP RES 2.2M J 1/16W 0402 | R2_SA;HF_SA;G_SA; | Released | TAI;CYNTEC;YAGEO;RALEC | RM04JTN225;RR0510S-225-JN;RC0402JR-072M2L;RTT02225JTH | Multiple |  | Purchase | SMT | 1 | PCS | PR68 |
| 2 | 55.B0701.S21G | 63.24134.15L | CHIP RES 240 J 1/10W 0603 | R2_SA;HF_SA;G_SA; | Released | TA-I ; RALEC ; YAGEO | RM06JTN241 ; RTT03241JTP ; RC0603JR-07240RL | Multiple |  | Purchase | SMT | 2 | PCS | R260 R266 |
| 2 | 55.B0701.S21G | 63.2R233.15L | CHIP RES 2.2 J 1/10W 0603 | R2_SA;HF_SA;G_SA; | Released | TA-I ; RALEC ; YAGEO ; WALSIN | RM06JTN2R2 ; RTT032R2JTP ; RC0603JR-072R2L ; WR06X2R2JTL | Multiple |  | Purchase | SMT | 5 | PCS | PR209 R113 R132 R361 R60 |
| 2 | 55.B0701.S21G | 63.2R234.1DL | CHIP RES 2.2 J 1/16W 0402 | R2_SA;HF_SA;G_SA; | Released | TA-I;RALEC;CYNTEC;YAGEO;WALSIN | RM04JTN2R2 ; RTT022R2JTH ; RR-0510S-2R2-JN ; RC0402JR-072R2L;WR04X2R2JTL | Multiple |  | Purchase | SMT | 2 | PCS | R202 R221 |
| 2 | 55.B0701.S21G | 63.51534.1DL | CHIP RES 5.1M J 1/16W 0402 | R2_SA;HF_SA;G_SA; | Released | RALEC ; CYNTEC ; TA-I ; WALSIN ; YAGEO | RTT02515JTH ; RR0510S-515-JN ; RM04JTN515 ; WR04X515JTL ; RC0402JR-075M1L | Multiple |  | Purchase | SMT | 1 | PCS | PR208 |
| 2 | 55.B0701.S21G | 63.75334.1DL | CHIP RES 75K J 1/16W 0402 | R2_SA;HF_SA;G_SA; | Released | TA-I ; RALEC ; CYNTEC;YAGEO | RM04JTN753 ; RTT02753JTH ; RR-0510S-753-JN ; RC0402JR-0775KL | Multiple |  | Purchase | SMT | 1 | PCS | PR141 |
| 2 | 55.B0701.S21G | 63.R0031.16L | CHIP RES 0 J 1/8W 0805 | R2_SA;HF_SA;G_SA; | Released | TA-I ; RALEC ; YAGEO ; WALSIN | RM10JTN0 ; RTT05000JTP ; RC0805JR-070RL ; WR08X000PTL | Multiple |  | Purchase | SMT | 1 | PCS | PR79 |
| 2 | 55.B0701.S21G | 63.R0032.11L | CHIP RES 0 J 1/4W 1206 (ROHS) | R2_SA;HF_SA;G_SA; | Released | TA-I ; RALEC ; YAGEO; WALSIN | RM12JTN0 ; RTT06000JTP ; RC1206JR-070RL; WR12X000 PTL | Multiple |  | Purchase | SMT | 4 | PCS | PR191 PR194 PR221 PR31 |
| 2 | 55.B0701.S21G | 63.R0033.15L | CHIP RES 0 J 1/10W 0603 | R2_SA;HF_SA;G_SA; | Released | YAGEO;RALEC;TAI | RC0603JR-130RL;RTT03000JTP;RM06JTN0 | Multiple |  | Purchase | SMT | 12 | PCS | PR107 PR132 PR136 PR146 PR153 PR163 PR173 PR179 PR181 PR187 PR225 PR226 |
| 2 | 55.B0701.S21G | 63.R0034.1DL | CHIP RES 0 J 1/16W 0402 | R2_SA;HF_SA;G_SA; | Released | TA-I;RALEC;CYNTEC;YAGEO;WALSIN | RM04JTN0;RTT02000JTH;RR0510X-000-XN;RC0402JR-070RL;WR04X000PTL | Multiple |  | Purchase | SMT | 162 | PCS | PR108 PR11 PR113 PR119 PR123 PR124 PR128 PR129 PR131 PR133 PR134 PR137 PR142 PR143 PR152 PR154 PR157 PR158 PR160 PR162 PR165 PR166 PR171 PR178 PR180 PR182 PR189 PR20 PR205 PR21 PR217 PR219 PR22 PR220 PR23 PR3 PR35 PR37 PR38 PR4 PR41 PR42 PR43 PR44 PR45 PR47 PR48 PR49 PR5 PR62 PR63 PR67 PR71 PR72 PR74 PR75 PR8 PR82 PR84 PR85 PR89 PR99 R100 R104 R118 R120 R125 R128 R129 R133 R134 R135 R136 R142 R15 R165 R166 R174 R179 R180 R184 R189 R190 R191 R193 R194 R200 R201 R217 R218 R222 R223 R225 R226 R236 R238 R242 R249 R257 R259 R262 R264 R265 R268 R283 R288 R300 R302 R304 R307 R322 R324 R329 R340 R35 R352 R36 R37 R370 R382 R383 R384 R39 R391 R392 R393 R395 R396 R398 R4 R40 R404 R407 R411 R412 R413 R417 R435 R436 R442 R443 R460 R472 R473 R476 R48 R481 R482 R483 R49 R494 R50 R52 R54 R55 R56 R58 R61 R62 R8 R84 R97 |
| 2 | 55.B0701.S21G | 64.10005.55L | CHIP RES 100 F 1/10W 0603 | R2_SA;HF_SA;G_SA; | Released | TAI;RALEC;YAGEO | RM06FTN1000;RTT031000FTP;RC0603FR-07100RL | Multiple |  | Purchase | SMT | 5 | PCS | PR1 PR12 PR88 PR94 R245 |
| 2 | 55.B0701.S21G | 64.10005.6DL | CHIP RES 100 F 1/16W 0402 | R2_SA;HF_SA;G_SA; | Released | TA-I ; RALEC ; CYNTEC ; YAGEO;WALSIN | RM04FTN1000 ; RTT021000FTH ; RR0510S-1000-FN ; RC0402FR-07100RL;WR04X1000FTL | Multiple |  | Purchase | SMT | 18 | PCS | PR211 PR212 PR214 PR29 R160 R161 R203 R220 R23 R233 R237 R24 R281 R289 R374 R385 R386 R90 |
| 2 | 55.B0701.S21G | 64.10015.16L | CHIP RES 1K F 1/8W 0805(ROHS) | R2_SA;HF_SA;G_SA; | Released | YAGEO;RALEC;TAI | RC0805FR-071KL;RTT051001FTP;RM10FTN1001 | Multiple |  | Purchase | SMT | 1 | PCS | R1 |
| 2 | 55.B0701.S21G | 64.10015.6DL | CHIP RES 1K F 1/16W 0402 | R2_SA;HF_SA;G_SA; | Released | TA-I;RALEC;CYNTEC;YAGEO;WALSIN | RM04FTN1001 ; RTT021001FTH ; RR0510S-102-FN ; RC0402FR-071KL;WR04X1001FTL | Multiple |  | Purchase | SMT | 37 | PCS | PR2 PR93 R102 R103 R13 R14 R163 R239 R240 R241 R244 R248 R253 R255 R274 R275 R276 R280 R294 R32 R33 R336 R338 R342 R356 R360 R367 R378 R402 R42 R434 R471 R506 R79 R80 R83 R88 |
| 2 | 55.B0701.S21G | 64.10025.6DL | CHIP RES 10K F 1/16W 0402 | R2_SA;HF_SA;G_SA; | Released | TA-I;RALEC;CYNTEC;YAGEO;WALSIN | RM04FTN1002 ; RTT021002FTH ; RR0510S-103-FN ; RC0402FR-0710KL;WR04X1002FTL | Multiple |  | Purchase | SMT | 56 | PCS | PR110 PR138 PR155 PR172 PR177 PR19 PR196 PR199 PR207 PR216 PR218 PR222 PR24 PR46 PR50 PR51 PR65 PR7 PR90 PR91 R112 R121 R123 R130 R138 R139 R144 R146 R159 R164 R172 R177 R214 R224 R250 R323 R362 R375 R410 R439 R46 R477 R478 R484 R486 R496 R497 R503 R53 R63 R75 R76 R77 R78 R82 R94 |
| 2 | 55.B0701.S21G | 64.10026.6DL | CHIP RES 10K D 1/16W 0402 | R2_SA;HF_SA;G_SA; | Released | CYNTEC;RALEC;TA-I;WALSIN;YAGEO | RR0510Q-103-DN;RTT021002DTH;RM04DTN1002;WF04H1002DTL;RT0402DRE0710KL | Multiple |  | Purchase | SMT | 1 | PCS | PR106 |
| 2 | 55.B0701.S21G | 64.10035.6DL | CHIP RES 100K F 1/16W 0402 | R2_SA;HF_SA;G_SA; | Released | TA-I;RALEC;CYNTEC;YAGEO;WALSIN | RM04FTN1003 ; RTT021003FTH ; RR0510S-104-FN ; RC0402FR-07100KL;WR04X1003FTL | Multiple |  | Purchase | SMT | 3 | PCS | R162 R261 R333 |
| 2 | 55.B0701.S21G | 64.10045.55L | CHIP RES 1M F 1/10W 0603 | R2_SA;HF_SA;G_SA; | Released | TAI;RALEC;YAGEO;WALSIN | RM06FTN1004;RTT031004FTP;RC0603FR-071ML;WR06X1004FTL | Multiple |  | Purchase | SMT | 1 | PCS | R331 |
| 2 | 55.B0701.S21G | 64.10055.55L | CHIP RES 10M F 1/10W 0603 | R2_SA;HF_SA;G_SA; | Released | TA-I ; RALEC ; YAGEO | RM06FTN1005 ; RTT031005FTP ; RC0603FR-0710ML | Multiple |  | Purchase | SMT | 1 | PCS | R92 |
| 2 | 55.B0701.S21G | 64.10R05.55L | CHIP RES 10 F 1/10W 0603 | R2_SA;HF_SA;G_SA; | Released | TA-I;RALEC;YAGEO;WALSIN | RM06FTN10R0 ; RTT0310R0FTP ; RC0603FR-0710RL;WR06X10R0FTL | Multiple |  | Purchase | SMT | 3 | PCS | PR200 PR60 PR61 |
| 2 | 55.B0701.S21G | 64.10R05.6DL | CHIP RES 10 F 1/16W 0402 | R2_SA;HF_SA;G_SA; | Released | TA-I ; RALEC ; CYNTEC ; YAGEO | RM04FTN10R0 ; RTT0210R0FTH ; RR0510S-100-FN ; RC0402FR-0710RL | Multiple |  | Purchase | SMT | 7 | PCS | PR117 PR159 PR164 PR176 PR18 PR81 PR83 |
| 2 | 55.B0701.S21G | 64.10R75.6DL | CHIP RES 10.7 F 1/16W 0402 | R2_SA;HF_SA;G_SA; | Released | TA-I;RALEC;CYNTEC;YAGEO | RM04FTN10R7 ; RTT0210R7FTH ; RR0510S-10R7-FN ; RC0402FR-0710R7L | Multiple |  | Purchase | SMT | 3 | PCS | PR102 PR126 PR40 |
| 2 | 55.B0701.S21G | 64.11025.6DL | CHIP RES 11K F 1/16W 0402 | R2_SA;HF_SA;G_SA; | Released | TA-I ; RALEC ; CYNTEC ; YAGEO;WALSIN | RM04FTN1102 ; RTT021102FTH ; RR0510S-1102-FN ; RC0402FR-0711KL;WR04X1102FTL | Multiple |  | Purchase | SMT | 4 | PCS | PR17 PR210 PR73 R335 |
| 2 | 55.B0701.S21G | 64.1183D.55L | CHIP RES 118K B 1/10W 0603 | R2_SA;HF_SA;G_SA; | Released | TA-I;RALEC;YAGEO | RM06BTN1183;RTT031183BTP;RT0603BRD07118KL | Multiple |  | Purchase | SMT | 1 | PCS | PR184 |
| 2 | 55.B0701.S21G | 64.12005.55L | CHIP RES 120 F 1/10W 0603 | R2_SA;HF_SA;G_SA; | Released | TA-I ; RALEC ; YAGEO | RM06FTN1200 ; RTT031200FTP ; RC0603FR-07120RL | Multiple |  | Purchase | SMT | 2 | PCS | PR33 PR78 |
| 2 | 55.B0701.S21G | 64.12125.6DL | CHIP RES 12.1K F 1/16W 0402 | R2_SA;HF_SA;G_SA; | Released | TA-I ; RALEC ; CYNTEC ; YAGEO ; WALSIN | RM04FTN1212 ; RTT021212FTH ; RR0510S-1212-FN ; RC0402FR-0712K1L ; WR04X1212FTL | Multiple |  | Purchase | SMT | 2 | PCS | R208 R209 |
| 2 | 55.B0701.S21G | 64.13015.6DL | CHIP RES 1.3K F 1/16W 0402(ROH | R2_SA;HF_SA;G_SA; | Released | TAI;RALEC;CYNTEC;YAGEO | RM04FTN1301;RTT021301FTH;RR0510S-132-FN;RC0402FR-071K3L | Multiple |  | Purchase | SMT | 1 | PCS | PR28 |
| 2 | 55.B0701.S21G | 64.13725.6DL | CHIP RES 13.7K F 1/16W 0402 | R2_SA;HF_SA;G_SA; | Released | TA-I;RALEC;CYNTEC;YAGEO | RM04FTN1372;RTT021372FTH;RR0510S-1372-FN;RC0402FR-0713K7L | Multiple |  | Purchase | SMT | 1 | PCS | PR26 |
| 2 | 55.B0701.S21G | 64.14005.6DL | CHIP RES 140 F 1/16W 0402 | R2_SA;HF_SA;G_SA; | Released | TA-I ; RALEC ; CYNTEC ; YAGEO | RM04FTN1400 ; RTT021400FTH ; RR0510S-1400-FN ; RC0402FR-07140RL | Multiple |  | Purchase | SMT | 1 | PCS | PR69 |
| 2 | 55.B0701.S21G | 64.15005.55L | CHIP RES 150 F 1/10W 0603(ROHS | R2_SA;HF_SA;G_SA; | Released | TAI;RALEC;YAGEO;WALSIN | RM06FTN1500;RTT031500FTP;RC0603FR-07150RL;WR06X1500FTL | Multiple |  | Purchase | SMT | 2 | PCS | R500 R501 |
| 2 | 55.B0701.S21G | 64.15015.6DL | CHIP RES 1.5K F 1/16W 0402 | R2_SA;HF_SA;G_SA; | Released | TA-I;RALEC;CYNTEC;YAGEO;WALSIN | RM04FTN1501 ; RTT021501FTH ; RR0510S-152-FN ; RC0402FR-071K5L;WR04X1501FTL | Multiple |  | Purchase | SMT | 1 | PCS | PR14 |
| 2 | 55.B0701.S21G | 64.15025.6DL | CHIP RES 15K F 1/16W 0402 | R2_SA;HF_SA;G_SA; | Released | TA-I;RALEC;CYNTEC;YAGEO | RM04FTN1502;RTT021502FTH;RR0510S-153-FN;RC0402FR-0715KL | Multiple |  | Purchase | SMT | 2 | PCS | PR195 PR96 |
| 2 | 55.B0701.S21G | 64.15035.6DL | CHIP RES 150K F 1/16W 0402 | R2_SA;HF_SA;G_SA; | Released | TA-I;RALEC;CYNTEC;YAGEO;WALSIN | RM04FTN1503 ; RTT021503FTH ; RR0510S-154-FN ; RC0402FR-07150KL;WR04X1503FTL | Multiple |  | Purchase | SMT | 1 | PCS | R18 |
| 2 | 55.B0701.S21G | 64.15R05.6DL | CHIP RES 15 F 1/16W 0402 | R2_SA;HF_SA;G_SA; | Released | TA-I;RALEC;CYNTEC;YAGEO | RM04FTN15R0;RTT0215R0FTH;RR0510S-150-FN;RC0402FR-0715RL | Multiple |  | Purchase | SMT | 1 | PCS | R169 |
| 2 | 55.B0701.S21G | 64.16205.6DL | CHIP RES 162 F 1/16W 0402 | R2_SA;HF_SA;G_SA; | Released | TA-I ; RALEC ; CYNTEC ; YAGEO | RM04FTN1620 ; RTT021620FTH ; RR0510S-1620-FN ; RC0402FR-07162RL | Multiple |  | Purchase | SMT | 2 | PCS | R303 R350 |
| 2 | 55.B0701.S21G | 64.18005.6DL | CHIP RES 180 F 1/16W 0402(ROHS | R2_SA;HF_SA;G_SA; | Released | TAI;YAGEO;RALEC;CYNTEC | RM04FTN1800;RC0402FR-07180RL;RTT021800FTH;RR0510S-1800-FN | Multiple |  | Purchase | SMT | 1 | PCS | PR77 |
| 2 | 55.B0701.S21G | 64.19115.6DL | CHIP RES 1.91K F 1/16W 0402 | R2_SA;HF_SA;G_SA; | Released | TAI;RALEC;CYNTEC;YAGEO;WALSIN | RM04FTN1911;RTT021911FTH;RR0510S-1911-FN;RC0402FR-071K91L;WR04X1911FTL | Multiple |  | Purchase | SMT | 2 | PCS | PR36 PR55 |
| 2 | 55.B0701.S21G | 64.19626.6DL | CHIP RES 19.6K D 1/16W 0402 | R2_SA;HF_SA;G_SA; | Released | TA-I ; RALEC ; YAGEO | RM04DTN1962 ; RTT021962DTH ; RC0402DR-0719K6L | Multiple |  | Purchase | SMT | 1 | PCS | PR70 |
| 2 | 55.B0701.S21G | 64.20025.6DL | CHIP RES 20K F 1/16W 0402 | R2_SA;HF_SA;G_SA; | Released | TA-I;RALEC;CYNTEC;YAGEO;WALSIN | RM04FTN2002 ; RTT022002FTH ; RR0510S-203-FN ; RC0402FR-0720KL;WR04X2002FTL | Multiple |  | Purchase | SMT | 6 | PCS | PR144 PR168 PR169 PR53 PR59 R17 |
| 2 | 55.B0701.S21G | 64.20035.6DL | CHIP RES 200K F 1/16W 0402 | R2_SA;HF_SA;G_SA; | Released | TA-I;RALEC;CYNTEC;YAGEO;WALSIN | RM04FTN2003 ; RTT022003FTH ; RR0510S-204-FN ; RC0402FR-07200KL;WR04X2003FTL | Multiple |  | Purchase | SMT | 1 | PCS | PR6 |
| 2 | 55.B0701.S21G | 64.20045.6DL | CHIP RES 2M F 1/16W 0402 | R2_SA;HF_SA;G_SA; | Released | TA-I;RALEC;CYNTEC;YAGEO | RM04FTN2004;RTT022004FTH;RR0510S-2004-FN;RC0402FR-072ML | Multiple |  | Purchase | SMT | 1 | PCS | PR27 |
| 2 | 55.B0701.S21G | 64.22005.6DL | CHIP RES 220 F 1/16W 0402 | R2_SA;HF_SA;G_SA; | Released | TA-I;RALEC;CYNTEC;YAGEO | RM04FTN2200;RTT022200FTH;RR0510S-2200-FN;RC0402FR-07220RL | Multiple |  | Purchase | SMT | 1 | PCS | R291 |
| 2 | 55.B0701.S21G | 64.22015.6DL | CHIP RES 2.2K F 1/16W 0402 | R2_SA;HF_SA;G_SA; | Released | TA-I;RALEC;CYNTEC;YAGEO | RM04FTN2201;RTT022201FTH;RR0510S-222-FN;RC0402FR-072K2L | Multiple |  | Purchase | SMT | 7 | PCS | PR188 R116 R243 R319 R321 R495 R98 |
| 2 | 55.B0701.S21G | 64.22035.6DL | CHIP RES 220K F 1/16W 0402 | R2_SA;HF_SA;G_SA; | Released | TA-I;RALEC;CYNTEC;YAGEO | RM04FTN2203;RTT022203FTH;RR0510S-2203-FN;RC0402FR-07220KL | Multiple |  | Purchase | SMT | 1 | PCS | R405 |
| 2 | 55.B0701.S21G | 64.22115.6DL | CHIP RES 2.21K F 1/16W 0402 | R2_SA;HF_SA;G_SA; | Released | TA-I ; RALEC ; CYNTEC ; YAGEO | RM04FTN2211 ; RTT022211FTH ; RR0510S-2211-FN ; RC0402FR-072K21L | Multiple |  | Purchase | SMT | 1 | PCS | PR86 |
| 2 | 55.B0701.S21G | 64.22R05.6DL | CHIP RES 22 F 1/16W 0402(ROHS) | R2_SA;HF_SA;G_SA; | Released | TA-I;RALEC;CYNTEC;YAGEO | RM04FTN22R0;RTT0222R0FTH;RR0510S-220-FN;RC0402FR-0722RL | Multiple |  | Purchase | SMT | 2 | PCS | R292 R330 |
| 2 | 55.B0701.S21G | 64.23735.6DL | CHIP RES 237K F 1/16W 0402 | R2_SA;HF_SA;G_SA; | Released | TA-I ; RALEC ; CYNTEC ; YAGEO | RM04FTN2373 ; RTT022373FTH ; RR0510S-2373-FN ; RC0402FR-07237KL | Multiple |  | Purchase | SMT | 2 | PCS | PR151 PR183 |
| 2 | 55.B0701.S21G | 64.23R75.6DL | CHIP RES 23.7 F 1/16W 0402 | R2_SA;HF_SA;G_SA; | Released | TA-I;RALEC;CYNTEC;YAGEO | RM04FTN23R7;RTT0223R7FTH;RR0510S-23R7-FN;RC0402FR-0723R7L | Multiple |  | Purchase | SMT | 2 | PCS | R279 R380 |
| 2 | 55.B0701.S21G | 64.24905.6DL | CHIP RES 249 F 1/16W 0402 | R2_SA;HF_SA;G_SA; | Released | TAI;RALEC;CYNTEC;YAGEO | RM04FTN2490;RTT022490FTH;RR0510S-2490-FN;RC0402FR-07249RL | Multiple |  | Purchase | SMT | 1 | PCS | PR213 |
| 2 | 55.B0701.S21G | 64.26115.6DL | CHIP RES 2.61K F 1/16W 0402 | R2_SA;HF_SA;G_SA; | Released | TAI;RALEC;CYNTEC;YAGEO | RM04FTN2611;RTT022611FTH;RR0510S-2611-FN;RC0402FR-072K61L | Multiple |  | Purchase | SMT | 2 | PCS | PR215 PR95 |
| 2 | 55.B0701.S21G | 64.2R205.16L | CHIP RES 2.2 F 1/8W 0805 | R2_SA;HF_SA;G_SA; | Released | RALEC;TA-I;YAGEO | RTT052R20FTP;RM10FTN2R2;RC0805FR-072R2L | Multiple |  | Purchase | SMT | 1 | PCS | PR104 |
| 2 | 55.B0701.S21G | 64.30005.6DL | CHIP RES 300 F 1/16W 0402 | R2_SA;HF_SA;G_SA; | Released | CYNTEC;RALEC;TAI;YAGEO | RR0510S-301-FN;RTT023000FTH;RM04FTN3000;RC0402FR-07300RL | Multiple |  | Purchase | SMT | 15 | PCS | R131 R148 R149 R150 R151 R152 R153 R154 R155 R156 R305 R394 R400 R85 R89 |
| 2 | 55.B0701.S21G | 64.30015.6DL | CHIP RES 3K F 1/16W 0402 | R2_SA;HF_SA;G_SA; | Released | TA-I;RALEC;CYNTEC;YAGEO;WALSIN | RM04FTN3001;RTT023001FTH;RR0510S-302-FN;RC0402FR-073KL;WR04X3001FTL | Multiple |  | Purchase | SMT | 1 | PCS | R311 |
| 2 | 55.B0701.S21G | 64.30025.6DL | CHIP RES 30K F 1/16W 0402 | R2_SA;HF_SA;G_SA; | Released | TA-I;RALEC;CYNTEC;YAGEO;WALSIN | RM04FTN3002;RTT023002FTH;RR0510S-303-FN;RC0402FR-0730KL;WR04X3002FTL | Multiple |  | Purchase | SMT | 1 | PCS | R43 |
| 2 | 55.B0701.S21G | 64.30125.6DL | CHIP RES 30.1K F 1/16W 0402 | R2_SA;HF_SA;G_SA; | Released | TA-I ; RALEC ; CYNTEC ; YAGEO | RM04FTN3012 ; RTT023012FTH ; RR0510S-3012-FN ; RC0402FR-0730K1L | Multiple |  | Purchase | SMT | 1 | PCS | PR228 |
| 2 | 55.B0701.S21G | 64.30R15.6DL | CHIP RES 30.1 F 1/16W 0402 | R2_SA;HF_SA;G_SA; | Released | TA-I ; RALEC ; CYNTEC ; YAGEO | RM04FTN30R1 ; RTT0230R1FTH ; RR0510S-30R1-FN ; RC0402FR-0730R1L | Multiple |  | Purchase | SMT | 2 | PCS | R309 R381 |
| 2 | 55.B0701.S21G | 64.31625.6DL | CHIP RES 31.6K F 1/16W 0402 | R2_SA;HF_SA;G_SA; | Released | TA-I;RALEC;CYNTEC;YAGEO | RM04FTN3162;RTT023162FTH;RR0510S-3162-FN;RC0402FR-0731K6L | Multiple |  | Purchase | SMT | 1 | PCS | PR227 |
| 2 | 55.B0701.S21G | 64.33005.6DL | CHIP RES 330 F 1/16W 0402 | R2_SA;HF_SA;G_SA; | Released | CYNTEC;RALEC;TAI;YAGEO | RR0510S-331-FN;RTT023300FTH;RM04FTN3300;RC0402FR-07330RL | Multiple |  | Purchase | SMT | 1 | PCS | R263 |
| 2 | 55.B0701.S21G | 64.33015.55L | CHIP RES 3.3K F 1/10W 0603(ROH | R2_SA;HF_SA;G_SA; | Released | TAI;RALEC;YAGEO | RM06FTN3301;RTT033301FTP;RC0603FR-073K3L | Multiple |  | Purchase | SMT | 3 | PCS | PR167 PR64 R10 |
| 2 | 55.B0701.S21G | 64.33015.6DL | CHIP RES 3.3K F 1/16W 0402 | R2_SA;HF_SA;G_SA; | Released | TAI;RALEC;CYNTEC;YAGEO | RM04FTN3301;RTT023301FTH;RR0510S-332-FN;RC0402FR-073K3L | Multiple |  | Purchase | SMT | 2 | PCS | PR156 PR224 |
| 2 | 55.B0701.S21G | 64.33R05.6DL | CHIP RES 33 F 1/16W 0402 | R2_SA;HF_SA;G_SA; | Released | TA-I;RALEC;CYNTEC;YAGEO;WALSIN | RM04FTN33R0;RTT0233R0FTH;RR0510S-330-FN;RC0402FR-0733RL;WR04X33R0FTL | Multiple |  | Purchase | SMT | 30 | PCS | R101 R106 R109 R110 R115 R127 R16 R182 R188 R28 R286 R29 R290 R30 R31 R327 R328 R334 R349 R351 R354 R355 R368 R369 R376 R419 R420 R59 R65 R86 |
| 2 | 55.B0701.S21G | 64.34835.6DL | CHIP RES 348K F 1/16W 0402 | R2_SA;HF_SA;G_SA; | Released | TA-I;RALEC;CYNTEC;YAGEO | RM04FTN3483;RTT023483FTH;RR0510S-3483-FN;RC0402FR-07348KL | Multiple |  | Purchase | SMT | 1 | PCS | PR147 |
| 2 | 55.B0701.S21G | 64.36515.6DL | CHIP RES 3.65K F 1/16W 0402 | R2_SA;HF_SA;G_SA; | Released | CYNTEC ; RALEC ; TA-I ; YAGEO | RR0510S-3651-FN ; RTT023651FTH ; RM04FTN3651 ; RC0402FR-073K65L | Multiple |  | Purchase | SMT | 3 | PCS | PR148 PR16 PR98 |
| 2 | 55.B0701.S21G | 64.39015.6DL | CHIP RES 3.9K F 1/16W 0402 | R2_SA;HF_SA;G_SA; | Released | TA-I;RALEC;CYNTEC;YAGEO;WALSIN | RM04FTN3901;RTT023901FTH;RR0510S-3901-FN;RC0402FR-073K9L;WR04X3901FTL | Multiple |  | Purchase | SMT | 1 | PCS | PR192 |
| 2 | 55.B0701.S21G | 64.3R015.16L | CHIP RES 3.01 F 1/8W 0805 | R2_SA;HF_SA;G_SA; | Released | TA-I;RALEC | RM10FTN3R01;RTT053R01FTP | Multiple |  | Purchase | SMT | 2 | PCS | PR100 PR193 |
| 2 | 55.B0701.S21G | 64.40205.6DL | CHIP RES 402 F 1/16W 0402 | R2_SA;HF_SA;G_SA; | Released | TA-I;RALEC;CYNTEC;YAGEO | RM04FTN4020;RTT024020FTH;RR0510S-4020-FN;RC0402FR-07402RL | Multiple |  | Purchase | SMT | 4 | PCS | R282 R357 R364 R372 |
| 2 | 55.B0701.S21G | 64.40215.6DL | CHIP RES 4.02K F 1/16W 0402 | R2_SA;HF_SA;G_SA; | Released | TA-I;RALEC;CYNTEC;YAGEO;WALSIN | RM04FTN4021;RTT024021FTH;RR0510S-4021-FN;RC0402FR-074K02L;WR04X4021FTL | Multiple |  | Purchase | SMT | 1 | PCS | R254 |
| 2 | 55.B0701.S21G | 64.41215.6DL | CHIP RES 4.12K F 1/16W 0402 | R2_SA;HF_SA;G_SA; | Released | TA-I;RALEC;CYNTEC;YAGEO | RM04FTN4121;RTT024121FTH;RR0510S-4121-FN;RC0402FR-074K12L | Multiple |  | Purchase | SMT | 1 | PCS | PR139 |
| 2 | 55.B0701.S21G | 64.42215.6DL | CHIP RES 4.22K F 1/16W 0402 | R2_SA;HF_SA;G_SA; | Released | YAGEO;TA-I;CYNTEC;RALEC | RC0402FR-074K22L;RM04FTN4221;RR0510S-4221-FN;RTT024221FTH | Multiple |  | Purchase | SMT | 1 | PCS | PR186 |
| 2 | 55.B0701.S21G | 64.43205.6DL | CHIP RES 432 F 1/16W 0402 | R2_SA;HF_SA;G_SA; | Released | TAI;RALEC;CYNTEC;YAGEO | RM04FTN4320;RTT024320FTH;RR-0510S-4320-FN;RC0402FR-07432RL | Multiple |  | Purchase | SMT | 1 | PCS | R454 |
| 2 | 55.B0701.S21G | 64.43R25.6DL | CHIP RES 43.2 F 1/16W 0402 | R2_SA;HF_SA;G_SA; | Released | TA-I;RALEC;CYNTEC;YAGEO | RM04FTN43R2;RTT0243R2FTH;RR0510S-43R2-FN;RC0402FR-0743R2L | Multiple |  | Purchase | SMT | 10 | PCS | R418 R424 R425 R426 R427 R428 R429 R430 R431 R432 |
| 2 | 55.B0701.S21G | 64.44225.6DL | CHIP RES 44.2K F 1/16W 0402 | R2_SA;HF_SA;G_SA; | Released | TA-I;RALEC;CYNTEC;YAGEO;WALSIN | RTT024422FTH ; RR0510S-4422-FN ; RM04FTN4422 ; RC0402FR-0744K2L ; WR04X4422FTL | Multiple |  | Purchase | SMT | 1 | PCS | PR198 |
| 2 | 55.B0701.S21G | 64.45R35.6DL | CHIP RES 45.3 F 1/16W 0402 | R2_SA;HF_SA;G_SA; | Released | TA-I;RALEC;CYNTEC;YAGEO;WALSIN | RM04FTN45R3 ; RTT0245R3FTH ; RR0510S-45R3-FN ; RC0402FR-0745R3L ; WR04X45R3FTL | Multiple |  | Purchase | SMT | 1 | PCS | R299 |
| 2 | 55.B0701.S21G | 64.47015.6DL | CHIP RES 4.7K F 1/16W 0402 | R2_SA;HF_SA;G_SA; | Released | TA-I;RALEC;CYNTEC;YAGEO;WALSIN | RM04FTN4701;RTT024701FTH;RR0510S-472-FN;RC0402FR-074K7L;WR04X4701FTL | Multiple |  | Purchase | SMT | 74 | PCS | R105 R12 R124 R140 R141 R145 R157 R173 R178 R181 R185 R186 R195 R198 R228 R229 R232 R234 R26 R27 R3 R301 R306 R308 R310 R312 R313 R316 R318 R326 R341 R343 R363 R388 R390 R408 R409 R41 R415 R437 R438 R44 R441 R444 R445 R449 R451 R452 R455 R458 R459 R461 R465 R466 R467 R470 R474 R479 R485 R498 R499 R51 R57 R6 R64 R66 R67 R7 R70 R71 R74 R87 R91 R95 |
| 2 | 55.B0701.S21G | 64.47035.6DL | CHIP RES 470K F 1/16W 0402 | R2_SA;HF_SA;G_SA; | Released | TA-I;RALEC;CYNTEC;YAGEO;WALSIN | RM04FTN4703;RTT024703FTH;RR0510S-474-FN;RC0402FR-07470KL;WR04X4703FTL | Multiple |  | Purchase | SMT | 1 | PCS | PR15 |
| 2 | 55.B0701.S21G | 64.47515.6DL | CHIP RES 4.75K F 1/16W 0402 | R2_SA;HF_SA;G_SA; | Released | TA-I;RALEC;CYNTEC;YAGEO | RM04FTN4751;RTT024751FTH;RR0510S-4751-FN;RC0402FR-074K75L | Multiple |  | Purchase | SMT | 2 | PCS | PR185 PR223 |
| 2 | 55.B0701.S21G | 64.47535.6DL | CHIP RES 475K F 1/16W 0402 | R2_SA;HF_SA;G_SA; | Released | TA-I;RALEC;CYNTEC;YAGEO | RM04FTN4753;RTT024753FTH;RR0510S-4753-FN;RC0402FR-07475KL | Multiple |  | Purchase | SMT | 2 | PCS | PR118 PR204 |
| 2 | 55.B0701.S21G | 64.49915.6DL | CHIP RES 4.99K F 1/16W 0402 | R2_SA;HF_SA;G_SA; | Released | TA-I;RALEC;CYNTEC;YAGEO;WALSIN | RM04FTN4991 ; RTT024991FTH ; RR0510S-4991-FN ; RC0402FR-074K99L ; WR04X4991FTL | Multiple |  | Purchase | SMT | 1 | PCS | PR161 |
| 2 | 55.B0701.S21G | 64.49R95.6DL | CHIP RES 49.9 F 1/16W 0402 | R2_SA;HF_SA;G_SA; | Released | TA-I;RALEC;CYNTEC;YAGEO;WALSIN | RM04FTN49R9;RTT0249R9FTH;RR0510S-49R9-FN;RC0402FR-0749R9L;WR04X49R9FTL | Multiple |  | Purchase | SMT | 2 | PCS | R320 R34 |
| 2 | 55.B0701.S21G | 64.51015.6DL | CHIP RES 5.1K F 1/16W 0402 | R2_SA;HF_SA;G_SA; | Released | TA-I;RALEC;CYNTEC;YAGEO;WALSIN | RM04FTN5101 ; RTT025101FTH ; RR0510S-512-FN ; RC0402FR-075K1L;WR04X5101FTL | Multiple |  | Purchase | SMT | 1 | PCS | PR30 |
| 2 | 55.B0701.S21G | 64.51115.6DL | CHIP RES 5.11K F 1/16W 0402 | R2_SA;HF_SA;G_SA; | Released | TA-I ; RALEC ; CYNTEC ; YAGEO;WALSIN | RM04FTN5111 ; RTT025111FTH ; RR0510S-5111-FN ; RC0402FR-075K11L;WR04X5111FTL | Multiple |  | Purchase | SMT | 1 | PCS | PR140 |
| 2 | 55.B0701.S21G | 64.51R05.6DL | CHIP RES 51 F 1/16W 0402 | R2_SA;HF_SA;G_SA; | Released | TA-I;RALEC;CYNTEC;YAGEO;WALSIN | RM04FTN51R0;RTT0251R0FTH;RR0510S-510-FN;RC0402FR-0751RL;WR04X51R0FTL | Multiple |  | Purchase | SMT | 6 | PCS | R247 R251 R267 R269 R270 R277 |
| 2 | 55.B0701.S21G | 64.56015.6DL | CHIP RES 5.6K F 1/16W 0402(ROH | R2_SA;HF_SA;G_SA; | Released | TA-I;RALEC;CYNTEC;YAGEO;WALSIN | RM04FTN5601;RTT025601FTH;RR0510S-562-FN;RC0402FR-075K6L;WR04X5601FTL | Multiple |  | Purchase | SMT | 1 | PCS | PR76 |
| 2 | 55.B0701.S21G | 64.56R25.6DL | CHIP RES 56.2 F 1/16W 0402 | R2_SA;HF_SA;G_SA; | Released | TA-I;RALEC;CYNTEC;YAGEO | RM04FTN56R2;RTT0256R2FTH;RR0510S-56R2-FN;RC0402FR-0756R2L | Multiple |  | Purchase | SMT | 2 | PCS | R143 R293 |
| 2 | 55.B0701.S21G | 64.59015.6DL | CHIP RES 5.9K F 1/16W 0402 | R2_SA;HF_SA;G_SA; | Released | TA-I;RALEC;CYNTEC;YAGEO | RM04FTN5901;RTT025901FTH;RR0510S-5901-FN;RC0402FR-075K9L | Multiple |  | Purchase | SMT | 1 | PCS | PR34 |
| 2 | 55.B0701.S21G | 64.60415.6DL | CHIP RES 6.04K F 1/16W 0402 | R2_SA;HF_SA;G_SA; | Released | TA-I;RALEC;CYNTEC;YAGEO;WALSIN | RM04FTN6041;RTT026041FTH;RR0510S-6041-FN;RC0402FR-076K04L;WR04X6041FTL | Multiple |  | Purchase | SMT | 1 | PCS | PR125 |
| 2 | 55.B0701.S21G | 64.64916.6DL | CHIP RES 6.49K D 1/16W 0402 | R2_SA;HF_SA;G_SA; | Released | RALEC ; CYNTEC ; TA-I ; YAGEO | RTT026491DTH ; RR0510Q-6491-DN ; RM04DTN6491 ; RT0402DRE076K49L | Multiple |  | Purchase | SMT | 1 | PCS | PR103 |
| 2 | 55.B0701.S21G | 64.73225.6DL | CHIP RES 73.2K F 1/16W 0402 | R2_SA;HF_SA;G_SA; | Released | TA-I;RALEC;CYNTEC;YAGEO;WALSIN | RM04FTN7322;RTT027322FTH;RR0510S-7322-FN;RC0402FR-0773K2L;WR04X7322FTL | Multiple |  | Purchase | SMT | 1 | PCS | PR202 |
| 2 | 55.B0701.S21G | 64.78705.6DL | CHIP RES 787 F 1/16W 0402 | R2_SA;HF_SA;G_SA; | Released | RALEC;CYNTEC;TA-I;WALSIN;YAGEO | RTT027870FTH;RR0510S-7870-FN;RM04FTN7870;WR04X7870FTL;RC0402FR-07787RL | Multiple |  | Purchase | SMT | 1 | PCS | PR121 |
| 2 | 55.B0701.S21G | 64.78715.6DL | CHIP RES 7.87K F 1/16W 0402 | R2_SA;HF_SA;G_SA; | Released | TA-I;RALEC;CYNTEC;YAGEO | RM04FTN7871;RTT027871FTH;RR0510S-7871-FN;RC0402FR-077K87L | Multiple |  | Purchase | SMT | 1 | PCS | PR66 |
| 2 | 55.B0701.S21G | 64.78725.6DL | CHIP RES 78.7K F 1/16W 0402 | R2_SA;HF_SA;G_SA; | Released | TA-I;RALEC;CYNTEC;YAGEO | RM04FTN7872;RTT027872FTH;RR0510S-7872-FN;RC0402FR-0778K7L | Multiple |  | Purchase | SMT | 1 | PCS | PR116 |
| 2 | 55.B0701.S21G | 64.82015.6DL | CHIP RES 8.2K F 1/16W 0402 | R2_SA;HF_SA;G_SA; | Released | TAI;RALEC;CYNTEC;YAGEO | RM04FTN8201;RTT028201FTH;RR0510S-822-FN;RC0402FR-078K2L | Multiple |  | Purchase | SMT | 2 | PCS | R468 R69 |
| 2 | 55.B0701.S21G | 64.84515.6DL | CHIP RES 8.45K F 1/16W 0402 | R2_SA;HF_SA;G_SA; | Released | TA-I;RALEC;CYNTEC;YAGEO | RM04FTN8451;RTT028451FTH;RR0510S-8451-FN;RC0402FR-078K45L | Multiple |  | Purchase | SMT | 1 | PCS | PR145 |
| 2 | 55.B0701.S21G | 65.B07ZZ.054 | HONEY BADGER PANTHER+ DVT2 FPGA MODULE | N/A; | Released |  |  |  | E | Manufacture | SMT | 1 | PCS | DUMMY |
| 3 | 65.B07ZZ.054 | 53.B0707.021 | FW FPGA E06 FLASH | R2; | Released | TBD |  | Single |  | Manufacture |  | 1 | PCS |  |
| 3 | 65.B07ZZ.054 | 72.25Q64.A03 | IC FALSH MEM W25Q64FVZPIG WSON 8P | R2_C;HF_C; | Released | WINBOND | W25Q64FVZPIG | Single |  | Purchase | SMT | 1 | PCS | U17 |
| 2 | 55.B0701.S21G | 68.00084.771 | CHIP BEAD BLM41PG600SN1L MURAT | R2_SA; | Released | MURATA | BLM41PG600SN1L | Single |  | Purchase | SMT | 1 | PCS | PL7 |
| 2 | 55.B0701.S21G | 68.00084.831 | CHIP BEAD BLM21PG220SN1D (LF) | R2_SA;HF_SA; | Released | MURATA | BLM21PG220SN1D | Single |  | Purchase | SMT | 1 | PCS | PL9 |
| 2 | 55.B0701.S21G | 68.00084.A31 | CHIP BEAD BLM18PG121SN1D 0603 | R2_SA;HF_SA;G_SA; | Released | MURATA | BLM18PG121SN1D | Single |  | Purchase | SMT | 6 | PCS | L4 L5 L6 L7 L8 L9 |
| 2 | 55.B0701.S21G | 68.00143.041 | CHIP BEAD BLM18PG330SN1D MURAT | R2_SA;HF_SA;G_SA; | Released | MURATA | BLM18PG330SN1D | Single |  | Purchase | SMT | 9 | PCS | L1 L10 L11 L12 L13 L14 L2 L3 PL8 |
| 2 | 55.B0701.S21G | 68.1R010.20C | CHIP CHOKE 1.0UH MPLCG0630L1R0 | R2_SA;HF_SA; | Released | NEC;TOKIN | MPLCG0630L1R0 | Multiple |  | Purchase | SMT | 1 | PCS | PL1 |
| 2 | 55.B0701.S21G | 68.2R21B.10J | CHIP IND 2.2UH MMD-06CZ-2R2M-V | R2_SA;HF_SA;G_SA; | Released | MAGLAYER | MMD-06CZ-2R2M-V1W | Single |  | Purchase | SMT | 1 | PCS | PL6 |
| 2 | 55.B0701.S21G | 68.3012N.10C | CHIP IND 300NH FP1007R3-R30-R | R2_SA; | Released | COOPER | FP1007R3-R30-R | Single |  | Purchase | SMT | 2 | PCS | PL2 PL4 |
| 2 | 55.B0701.S21G | 68.R2210.201 | CHIP CHOCK0.22U PCMB042T-R22MS | R2_SA; | Released | CYNTEC | PCMB042T-R22MS | Single |  | Purchase | SMT | 1 | PCS | PL3 |
| 2 | 55.B0701.S21G | 68.R6810.20J | CHIP CHOKE 0.68UH PCMB063T-R68MS | R2_SA;HF_SA; | Released | CYNTEC | PCMB063T-R68MS | Single |  | Purchase | SMT | 1 | PCS | PL5 |
| 2 | 55.B0701.S21G | 69.60011.121 | THERM SMD 10K NCP15XH103F03RC | R2_SA;HF_SA; | Released | MURATA | NCP15XH103F03RC | Single |  | Purchase | SMT | 1 | PCS | PRT1 |
| 2 | 55.B0701.S21G | 69.60013.201 | THERM 100K TSM0B104F4251RZ 0402 SMD | R2_SA;HF_SA;G_SA; | Released | TKS | TSM0B104F4251RZ | Single |  | Purchase | SMT | 1 | PCS | PRT2 |
| 2 | 55.B0701.S21G | 71.09833.00W | IC BUF 9DB833AGILFT TSSOP 48P | R2_SA; | Released | IDT | 9DB833AGILFT | Single |  | Purchase | SMT | 1 | PCS | U28 |
| 2 | 55.B0701.S21G | 71.18602.00W | IC I2C BUS SC18IS602BIPW TSSOP | R2_SA; | Released | NXP | SC18IS602BIPW | Single |  | Purchase | SMT | 1 | PCS | U48 |
| 2 | 55.B0701.S21G | 72.24128.G01 | IC EEPRM M24128-BWMN6TP SO8 | R2_SA;HF_SA;G_SA; | Released | ST | M24128-BWMN6TP | Single |  | Purchase | SMT | 1 | PCS | U22 |
| 2 | 55.B0701.S21G | 72.25256.E01 | IC EEPROM AT25256B-SSHL-T SOIC | R2_SA; | Released | ATMEL | AT25256B-SSHL-T | Single |  | Purchase | SMT | 1 | PCS | U21 |
| 2 | 55.B0701.S21G | 73.01G07.01H | IC BUF SN74LVC1G07DCKRG4 DCK5P | R2_SA; | Released | TI | SN74LVC1G07DCKRG4 | Single |  | Purchase | SMT | 2 | PCS | U31 U4 |
| 2 | 55.B0701.S21G | 73.01G08.L03 | IC CMOS SN74LVC1G08DCKR SC-70 | R2_SA;HF_SA;G_SA; | Released | TI | SN74LVC1G08DCKR | Single |  | Purchase | SMT | 1 | PCS | U15 |
| 2 | 55.B0701.S21G | 73.01G11.AHH | IC CMOS SN74LVC1G11DCKR DCK | R_SA;G_SA; | Released | TI | SN74LVC1G11DCKR | Single |  | Purchase | SMT | 2 | PCS | U42 U43 |
| 2 | 55.B0701.S21G | 73.01G14.L05 | IC CMOS 74LVC1G14DCKR SC-70(GP | R2_SA;G_SA; | Released | TI | SN74LVC1G14DCKR | Single |  | Purchase | SMT | 5 | PCS | U10 U12 U2 U6 U7 |
| 2 | 55.B0701.S21G | 73.01G17.BHH | IC CMOS SN74LVC1G17DCKR DCK 5P | R2_SA;HF_SA; | Released | TI | SN74LVC1G17DCKR | Single |  | Purchase | SMT | 2 | PCS | U45 U46 |
| 2 | 55.B0701.S21G | 73.03257.003 | IC CMOS SN74CBTLV3257RGYR QFN | R2_SA; | Released | TI | SN74CBTLV3257RGYR | Single |  | Purchase | SMT | 1 | PCS | U50 |
| 2 | 55.B0701.S21G | 73.1G126.DHG | IC CMOS SN74LVC1G126DCKR SC70 | R2_SA;HF_SA; | Released | TI | SN74LVC1G126DCKR | Single |  | Purchase | SMT | 3 | PCS | U39 U40 U41 |
| 2 | 55.B0701.S21G | 74.00075.B79 | IC TEMP SENSOR TMP75AIDGKR MSOP 8P | R2_SA; | Released | TI | TMP75AIDGKR | Single |  | Purchase | SMT | 1 | PCS | U1 |
| 2 | 55.B0701.S21G | 74.00321.X1F | IC OP LMV321IDCKR SC70 5P | R2_SA;HF_SA; | Released | TI | LMV321IDCKR | Single |  | Purchase | SMT | 2 | PCS | U23 U27 |
| 2 | 55.B0701.S21G | 74.00538.073 | IC PWM EP53F8QI-T QFN 16P | R2_SA; | Released | ALTERA | EP53F8QI-T | Single |  | Purchase | SMT | 2 | PCS | PU11 PU13 |
| 2 | 55.B0701.S21G | 74.06337.073 | IC PWM EN6337QI QFN 38P | R2_SA; | Released | ALTERA | EN6337QI | Single |  | Purchase | SMT | 1 | PCS | PU1 |
| 2 | 55.B0701.S21G | 74.06353.A73 | IC PWM ISL6353CRTZ TQFN 40P(REV.VS11) | R2_SA; | Released | INTERSIL | ISL6353CRTZ | Single |  | Purchase | SMT | 1 | PCS | PU10 |
| 2 | 55.B0701.S21G | 74.07828.A4G | IC CONV ADS7828E/2K5 TSSOP 16P | R2_SA; | Released | TI | ADS7828E/2K5 | Single |  | Purchase | SMT | 1 | PCS | U19 |
| 2 | 55.B0701.S21G | 74.23157.A99 | IC A.S TS5A23157DGSR DGS 10P | R2_SA;G_SA; | Released | TI | TS5A23157DGSR | Single |  | Purchase | SMT | 1 | PCS | U33 |
| 2 | 55.B0701.S21G | 74.51200.071 | IC TERM REGU TPS51200 SON 10P | R2_SA; | Released | TI | TPS51200 | Single |  | Purchase | SMT | 2 | PCS | PU12 PU4 |
| 2 | 55.B0701.S21G | 74.53318.073 | IC PWR CTRL TPS53318DQPR QFN 22P | R2_SA;HF_SA; | Released | TI | TPS53318DQPR | Single |  | Purchase | SMT | 1 | PCS | PU15 |
| 2 | 55.B0701.S21G | 74.53319.073 | IC PWR CTRL TPS53319DQPR QFN 22P | R2_SA;HF_SA; | Released | TI | TPS53319DQPR | Single |  | Purchase | SMT | 1 | PCS | PU7 |
| 2 | 55.B0701.S21G | 74.74801.A33 | IC LDO TPS74801RGW QFN 20P | R2_SA; | Released | TI | TPS74801RGW | Single |  | Purchase | SMT | 2 | PCS | PU14 PU16 |
| 2 | 55.B0701.S21G | 74.79301.07P | IC LDO TPS79301DBVR SOT-23-6 | R2_SA; | Released | TI | TPS79301DBVR | Single |  | Purchase | SMT | 1 | PCS | PU17 |
| 2 | 55.B0701.S21G | 74.90727.B7P | IC XDCP ISL90727WIE627Z-TK SC-70 6P | R2_SA;HF_SA; | Obsoleted | INTERSIL | ISL90727WIE627Z-TK | Single |  | Purchase | SMT | 1 | PCS | U26 |
| 2 | 55.B0701.S21G | 74.95831.B73 | IC V.R ISL95831CHRTZ-TS2568 TQFN 48P | R2_SA; | Released | INTERSIL | ISL95831CHRTZ-TS2568 | Single |  | Purchase | SMT | 1 | PCS | PU3 |
| 2 | 55.B0701.S21G | 74.D1117.G3C | IC A.R LD1117AG-12-SOT-223 | R2_SA;HF_SA;G_SA; | Released | UTC | LD1117AG-12-AA3-A-R | Single |  | Purchase | SMT | 2 | PCS | PU8 PU9 |
| 2 | 55.B0701.S21G | 75.00054.E7D | IC DIODE S.B BAT54C-7-F SOT-23 3P | R2_SA;HF_SA;G_SA; | Released | DIODES | BAT54C-7-F | Single |  | Purchase | SMT | 1 | PCS | D1 |
| 2 | 55.B0701.S21G | 75.04253.075 | IC MOSFET IRFH4253DTRPBF PQFN 8P | R2_SA; | Released | IR | IRFH4253DTRPBF | Single |  | Purchase | SMT | 2 | PCS | PU2 PU6 |
| 2 | 55.B0701.S21G | 78.10134.1FL | CHIP CAP C 100P 50V J0402 NPO | R2_SA;HF_SA;G_SA; | Released | AVX;DARFON;MURATA;PHYCOMP;SAMSUNG;TAIYO;TDK;WALSIN;YAGEO | CM05CG101J50AH;C1005NP0101JGT;GRM1555C1H101JA01D;223886915101;CL05C101JB5NNNC;UMK105CH101JV-F;C1005C0G1H101JT;0402N101J500LT;CC0402JRNPO9BN101 | Multiple |  | Purchase | SMT | 2 | PCS | PC1 PC147 |
| 2 | 55.B0701.S21G | 78.10224.2FL | CHIP CAP C 1000P 50V K0402 X7R | R2_SA;HF_SA;G_SA; | Released | AVX;DARFON;MURATA;PHYCOMP;SAMSUNG;TAIYO;TDK;MURATA;AVX;YAGEO | CM05X7R102K50AH;C1005X7R102KGT;GRM155R71H102KA01D;223858715623;CL05B102KB5NNNC;UMK105BJ102KV-F;C1005X7R1H102KT000F;WBM155R71H102KA01D;04025C102KAT2A;CC0402KRX7R9BB102 | Multiple |  | Purchase | SMT | 12 | PCS | PC103 PC108 PC115 PC174 PC22 PC3 PC43 PC57 PC72 PC75 PC97 PC99 |
| 2 | 55.B0701.S21G | 78.10321.2FL | CHIP CAP C 0.01U 16V K0402 X7R | R2_SA;HF_SA;G_SA; | Released | AVX;DARFON;MURATA;PHYCOMP;SAMSUNG;TAIYO;TDK;WALSIN;MURATA;YAGEO | 0402YC103KAT2A;C1005X7R103KET;GRM155R71C103KA01D;223878715636;CL05B103KO5NNNC;EMK105BJ103KV-F;C1005X7R1C103KT000F;0402B103K160CT;WBM155R71C103KA01D;CC0402KRX7R7BB103 | Multiple |  | Purchase | SMT | 15 | PCS | C282 C283 C305 C306 C307 C308 C45 C48 C56 C58 C60 C64 PC14 PC211 PC79 |
| 2 | 55.B0701.S21G | 78.10421.2FL | CHIP CAP C 0.1U 16V K0402 X7R | R2_SA;HF_SA;G_SA; | Released | DARFON;MURATA;PHYCOMP;SAMSUNG;TAIYO;TDK;WALSIN;YAGEO | C1005X7R104KET;GRM155R71C104KA88D;223878715649;CL05B104KO5NNNC;EMK105BJ104KV-FR ;C1005X7R1C104KT000F;0402B104K160CT;CC0402KRX7R7BB104 | Multiple |  | Purchase | SMT | 91 | PCS | C107 C109 C120 C121 C127 C170 C173 C177 C183 C2 C200 C230 C231 C248 C249 C262 C263 C264 C265 C266 C267 C268 C269 C270 C271 C272 C273 C274 C275 C276 C277 C278 C279 C280 C281 C284 C285 C286 C287 C294 C295 C296 C303 C304 C311 C324 C325 C326 C327 C328 C329 C330 C331 C332 C333 C334 C340 C341 C342 C343 C344 C348 C349 C350 C351 C356 C358 C4 C69 C70 C71 C77 C78 C79 C83 C84 C85 C86 C93 C94 C95 PC114 PC125 PC128 PC190 PC195 PC205 PC53 PC54 PC63 PC9 |
| 2 | 55.B0701.S21G | 78.10422.2FL | CHIP CAP C 0.1U 25V K0402 X7R | R2_SA;HF_SA;G_SA; | Released | YAGEO;WALSIN;MURATA;TDK | CC0402KRX7R8BB104;0402B104K250CT;GRM155R71E104KE14D;C1005X7R1E104KT | Multiple |  | Purchase | SMT | 8 | PCS | C80 PC150 PC152 PC181 PC32 PC33 PC82 PC95 |
| 2 | 55.B0701.S21G | 78.10423.2FL | CHIP CAP C 0.1U 10V K0402 X7R | R2_SA;HF_SA;G_SA; | Released | MURATA;PHYCOMP;SAMSUNG;TAIYO;TDK;DARFON;WALSIN;MURATA;YAGEO | GRM155R71A104KA01D;223824715649;CL05B104KP5NNNC;RMLMK105BJ104KV-F;C1005X7R1A104KT000F;C1005X7R104KDT;0402B104K100CT;WBM155R71A104KA01D;CC0402KRX7R6BB104 | Multiple |  | Purchase | SMT | 64 | PCS | C10 C11 C12 C13 C134 C135 C136 C138 C139 C140 C144 C149 C15 C162 C164 C165 C172 C18 C192 C197 C201 C206 C207 C208 C209 C21 C223 C23 C232 C233 C234 C235 C236 C25 C27 C28 C29 C309 C310 C314 C317 C323 C335 C336 C337 C338 C339 C35 C41 C46 C49 C51 C52 C54 C6 C61 C62 C72 C73 C74 C8 C82 PC138 PC203 |
| 2 | 55.B0701.S21G | 78.10424.2BL | CHIP CAP C 0.1U 50V K0603 X7R | R2_SA;HF_SA;G_SA; | Released | MURATA;TDK;AVX;PHYCOMP;SAMSUNG;DARFON;MATSUKI;WALSIN | GRM188R71H104KA93D;C1608X7R1H104KT000N;06035C104KAT2A;223858615649;CL10B104KB8NNNC;C1608X7R104KGT;MAG03X7R1H104K;0603B104K500CT | Multiple |  | Purchase | SMT | 3 | PCS | PC164 PC50 PC78 |
| 2 | 55.B0701.S21G | 78.10431.2FL | CHIP CAP 0.1UF J 16V 0402 X7R | R2_SA;HF_SA;G_SA; | Released | KEMET;TDK;MURATA;PHYCOMP;DARFON;SAMSUNG;WALSIN | C0402C104J4RAC;C1005X7R1C104JT;GRM155R71C104JA88D;223878715549;C1005X7R104JET;CL05B104JO5NNNC;0402B104J160CT | Multiple |  | Purchase | SMT | 3 | PCS | C143 C154 C257 |
| 2 | 55.B0701.S21G | 78.10520.2BL | CHIP CAP C 1U 6.3V K0603 X7R | R2_SA;HF_SA;G_SA; | Released | MURATA;TAIYO;DARFON;WALSIN;PHYCOMP;SAMSUNG | GRM188R70J105K;JMK107B7105KA-T;C1608X7R105KCT;0603B105K6R3CT;225520615663;CL10B105KQ8NNNC | Multiple |  | Purchase | SMT | 5 | PCS | C352 C353 C354 C355 C357 |
| 2 | 55.B0701.S21G | 78.10520.5FL | CHIP CAP C 1U 6.3V K0402 X5R | R2_SA;HF_SA;G_SA; | Released | TDK;TAIYO;PHYCOMP;DARFON;MURATA;SAMSUNG;MATSUKI;WALSIN;YAGEO;AVX | C1005X5R0J105KT;JMK105BJ105KV-F;225520713663;C1005X5R105KCT;GRM155R60J105KE19D;CL05A105KQ5NNNC;MAG02X5R0J105K;0402X105K6R3CT;CC0402KRX5R5BB105;CM05X5R105K06AT | Multiple |  | Purchase | SMT | 13 | PCS | C102 C137 C247 C250 C291 C30 C302 C31 C87 C92 C96 C98 PC209 |
| 2 | 55.B0701.S21G | 78.10521.2BL | CHIP CAP C 1U 16V K0603 X7R | R2_SA;HF_SA;G_SA; | Released | KEMET;MURATA;TAIYO;TDK;PHYCOMP;WALSIN;SAMSUNG;DARFON | C0603C105K4RAC;GRM188R71C105KA12D;EMK107B7105KA-T;C1608X7R1C105KT;223878615663;0603B105K160CT;CL10B105KO8NNNC;C1608X7R105KET | Multiple |  | Purchase | SMT | 6 | PCS | PC106 PC110 PC127 PC35 PC65 PC93 |
| 2 | 55.B0701.S21G | 78.10521.5FL | CHIP CAP C 1U 16V K0402 X5R | R2_SA;HF_SA;G_SA; | Released | TAIYO;AVX;SAMSUNG;DARFON;MURATA | EMK105BJ105KV-F;CV05X5R105K16AH;CL05A105KO5NNNC;C1005X5R105KET;GRM155R61C105KA12D | Multiple |  | Purchase | SMT | 1 | PCS | PC89 |
| 2 | 55.B0701.S21G | 78.10522.2BL | CHIP CAP C 1U 25V K0603 X7R | R2_SA;HF_SA;G_SA; | Released | MURATA;TAIYO;TDK;WALSIN;SAMSUNG;DARFON | GRM188R71E105KA12D;TMK107BJ105KA-T;C1608X7R1E105KT;CL10B105KA8NNNC;C1608X7R105KFT | Multiple |  | Purchase | SMT | 5 | PCS | C119 C16 C20 C227 C258 |
| 2 | 55.B0701.S21G | 78.10523.5FL | CHIP CAP C 1U 10V K0402 X5R | R2_SA;HF_SA;G_SA; | Released | MURATA;TDK;DARFON;MATSUKI;PHYCOMP;TAIYO;SAMSUNG;WALSIN | GRM155R61A105KE15D;C1005X5R1A105KT;C1005X5R105KDT;MAG02X5R1A105K;223824713663;LMK105BJ105KVF;CL05A105KP5NNNC;0402X105K100CT | Multiple |  | Purchase | SMT | 83 | PCS | C101 C114 C118 C123 C124 C128 C129 C130 C131 C132 C133 C14 C142 C145 C146 C147 C148 C150 C151 C152 C153 C155 C156 C157 C160 C163 C166 C167 C169 C171 C174 C175 C176 C178 C180 C182 C186 C187 C190 C193 C194 C195 C198 C202 C203 C204 C211 C212 C213 C215 C216 C217 C218 C219 C22 C220 C221 C224 C225 C226 C228 C229 C237 C238 C239 C240 C241 C242 C243 C245 C246 C252 C253 C254 C256 C259 C261 C297 C299 C76 C99 PC185 PC8 |
| 2 | 55.B0701.S21G | 78.10610.5BL | CHIP CAP C 10U 6.3V M0603 X5R | R2_SA;HF_SA;G_SA; | Released | DARFON;MATSUKI;MURATA;PHYCOMP;SAMSUNG;TAIYO;TDK;AVX;YAGEO | C1608X5R106MCT;MAG03X5R0J106M;GRM188R60J106ME47D;225520613776;CL10A106MQ8NNNC;JMK107BJ106MA-T;C1608X5R0J106MT0A0E;CV105X5R106M06AT;CC0603MRX5R5BB106 | Multiple |  | Purchase | SMT | 52 | PCS | C100 C103 C104 C105 C106 C108 C110 C111 C112 C116 C117 C24 C255 C288 C289 C290 C292 C293 C298 C300 C301 C36 C43 C53 C67 C68 C90 C91 C97 PC117 PC118 PC119 PC140 PC142 PC143 PC146 PC153 PC154 PC156 PC158 PC167 PC168 PC169 PC178 PC179 PC204 PC206 PC207 PC208 PC45 PC49 PC52 |
| 2 | 55.B0701.S21G | 78.10620.21L | CHIP CAP C 10U 6.3V K0805 X7R | R2_SA;HF_SA;G_SA; | Released | MURATA;TAIYO;DARFON;AVX KYOCERA | GRM21BR70J106K;JMK212B7106KG-T;C2012X7R106KC; CM21X7R106K06AT | Multiple |  | Purchase | SMT | 18 | PCS | C158 C159 PC129 PC130 PC133 PC134 PC139 PC141 PC196 PC198 PC199 PC200 PC201 PC202 PC21 PC26 PC88 PC98 |
| 2 | 55.B0701.S21G | 78.10621.22L | CHIP CAP C 10U 16V K1206 X7R | R2_SA;HF_SA;G_SA; | Released | MURATA;TDK;AVX;DARFON;SAMSUNG;TAIYO | GRM31CR71C106KA12L;C3216X7R1C106KT;CM316X7R106K16AT;C3216X7R106KEP;CL31B106KOHNNNE;EMK316B7106KL-T | Multiple |  | Purchase | SMT | 2 | PCS | PC111 PC62 |
| 2 | 55.B0701.S21G | 78.10622.51L | CHIP CAP C 10U 25V K0805 X5R | R2_SA;HF_SA;G_SA; | Released | MATSUKI;SUMSUNG;TAIYO;AVX;MURATA;TDK | MAG05X5R1E106K ; CL21A106KAYNNNE ; TMK212BJ106KG-TD;CM21X5R106K25AT;GRM21BR61E106KA73L;C2012X5R1E106KT | Multiple |  | Purchase | SMT | 6 | PCS | C39 PC165 PC175 PC18 PC20 PC23 |
| 2 | 55.B0701.S21G | 78.10710.52L | CHIP CAP C 100U 6.3V M1206 X5R | R2_SA;HF_SA;G_SA; | Released | MURATA;TAIYO | GRM31CR60J107ME39L;JMK316BJ107ML | Multiple |  | Purchase | SMT | 3 | PCS | PC73 PC77 PC80 |
| 2 | 55.B0701.S21G | 78.10710.53L | CHIP CAP C 100U 6.3V M1210 X5R | R2_SA;HF_SA;G_SA; | Released | MURATA;TAIYO;TDK;KEMET;TAIYO;SAMSUNG | GRM32ER60J107ME20L;JMK325BJ107MM-T;C3225X5R0J107MT000N;C1210C107M9PAC;JMK325ABJ107MM-P;CL32A107MQVNNNE | Multiple |  | Purchase | SMT | 2 | PCS | PC157 PC180 |
| 2 | 55.B0701.S21G | 78.15044.1FL | CHIP CAP C 15P 50V G0402 NPO | R2_SA;HF_SA;G_SA; | Released | DARFON;MURATA;PHYCOMP | C1005NP0150GGT;GRM1555C1H150GA01D;223886914159 | Multiple |  | Purchase | SMT | 1 | PCS | PC4 |
| 2 | 55.B0701.S21G | 78.15124.2FL | CHIP CAP C 150P 50V K0402 X7R | R2_SA;HF_SA;G_SA; | Released | AVX;PHYCOMP;DARFON | 04025C151KAT2A;223858715612;C1005X7R151KGT | Multiple |  | Purchase | SMT | 1 | PCS | PC58 |
| 2 | 55.B0701.S21G | 78.15224.2FL | CHIP CAP C 1500P 50V K0402 X7R | R2_SA;HF_SA;G_SA; | Released | MURATA;AVX;TDK;TAYIO;PHYCOMN;DARFON;WALSIN | GRM155R71H152KA01D;04025C152KAT2A;C1005X7R1H152KT000F;UMK105BJ152KV-F;223858715625;C1005X7R152KGT;0402B152K500CT | Multiple |  | Purchase | SMT | 1 | PCS | PC192 |
| 2 | 55.B0701.S21G | 78.15322.2FL | CHIP CAP C 0.015U 25V K0402 X7R | R2_SA;HF_SA;G_SA; | Released | MURATA;TDK;WALSIN;DARFON;PHYCOMP | GRM155R71E153KA61D;C1005X7R1E153KT000F;0402B153K250CT;C1005X7R153KFT;223891715638 | Multiple |  | Purchase | SMT | 1 | PCS | PC122 |
| 2 | 55.B0701.S21G | 78.22044.1FL | CHIP CAP C 22P 50V G0402 NPO | R2_SA;HF_SA;G_SA; | Released | DARFON ; PHYCOMP ; YAGEO ; WALSIN | C1005NP0220GGT ; 223886914229 ; CC0402GRNPO9BN220 ; 0402N220G500CT | Multiple |  | Purchase | SMT | 1 | PCS | PC210 |
| 2 | 55.B0701.S21G | 78.22124.2FL | CHIP CAP C 220P 50V K0402 X7R | R2_SA;HF_SA;G_SA; | Released | MURATA;AVX;TAIYO;PHYCOMN;DARFON | GRM155R71H221KA01D;04025C221KAT2A;UMK105BJ221KV-F;223858715614;C1005X7R221KGT | Multiple |  | Purchase | SMT | 1 | PCS | PC10 |
| 2 | 55.B0701.S21G | 78.22321.2FL | CHIP CAP 0.022U 16V K0402 X7R | R2_SA;HF_SA;G_SA; | Released | AVX;MURATA;PHYCOMP;TAIYO;TDK;DARFON;WALSIN | 0402YC223KAT2A;GRM155R71C223KA01D;223878715641;EMK105BJ223KV-F(EMK105B7223KV-F);C1005X7R1C223KT;C1005X7R223KET;0402B223K160CT | Multiple |  | Purchase | SMT | 2 | PCS | PC16 PC17 |
| 2 | 55.B0701.S21G | 78.22421.2BL | CHIP CAP C 0.22U 16V K0603 X7R | R2_SA;HF_SA;G_SA; | Released | MURATA;TAIYO;TDK;PHYCOMP;DARFON | GRM188R71C224KA01D;EMK107B7224KA-T;C1608X7R1C224KT;223878615654;C1608X7R224KET | Multiple |  | Purchase | SMT | 4 | PCS | PC109 PC13 PC46 PC56 |
| 2 | 55.B0701.S21G | 78.22421.2FL | CHIP CAP C 0.22U 16V K0402 X7R | R2_SA;HF_SA;G_SA; | Released | MURATA;TDK;SAMSUNG;DARFON;TAIYO | GRM155R71C224KA12D;C1005X7R1C224KT;CL05B224KO5NNNC;C1005X7R224KET;EMK105B7224KV-FR | Multiple |  | Purchase | SMT | 1 | PCS | C75 |
| 2 | 55.B0701.S21G | 78.22423.5FL | CHIP CAP C 0.22U 10V K0402 X5R | R2_SA;HF_SA;G_SA; | Released | MURATA;TDK;TAIYO;PHYCOMN;DARFON;WALSIN | GRM155R61A224KE19D;C1005X5R1A224KT000E;LMK105BJ224KV-F;223824713654;C1005X5R224KDT;0402X224K100CT | Multiple |  | Purchase | SMT | 4 | PCS | PC24 PC48 PC55 PC70 |
| 2 | 55.B0701.S21G | 78.22523.5FL | CHIP CAP C 2.2U 10V K0402 X5R | R2_SA;HF_SA;G_SA; | Released | DARFON;TAIYO;PHYCOMP;WALSIN;MURATA | C1005X5R225KDT;LMK105BJ225MV-F;225524713667;0402X225K100CT;GRM155R61A225KE95D | Multiple |  | Purchase | SMT | 8 | PCS | C185 C191 C199 C205 C210 C214 C251 C5 |
| 2 | 55.B0701.S21G | 78.22610.51L | CHIP CAP C 22U 6.3V M0805 X5R | R2_SA;HF_SA;G_SA; | Released | MURATA;TAIYO;TDK;KEMET;PANASONIC;MATSUKI;SAMSUNG;DARFON;WALSIN;YAGEO;AVX | GRM21BR60J226ME39L;JMK212BJ226MG-T;C2012X5R0J226MT;C0805C226M9PAC;ECJ2FB0J226M;MAG05X5R0J226M;CL21A226MQQNNNE;C2012X5R226MCP;0805X226M6R3CT;CC0805MKX5R5BB226;CV21X5R226M06AT | Multiple |  | Purchase | SMT | 24 | PCS | C126 C161 C168 C179 C188 C260 C9 PC100 PC112 PC113 PC120 PC123 PC124 PC155 PC160 PC161 PC162 PC163 PC166 PC170 PC171 PC177 PC83 PC96 |
| 2 | 55.B0701.S21G | 78.22610.5BL | CHIP CAP C 22U 6.3V M0603 X5R | R2_SA;HF_SA;G_SA; | Released | MURATA;TDK;SAMSUNG;TAIYO;DARFON | GRM188R60J226MEA0D;C1608X5R0J226MT;CL10A226MQ8NRNC;JDK107BBJ226MA-T;C1608X5R226MCT | Multiple |  | Purchase | SMT | 6 | PCS | PC149 PC36 PC42 PC44 PC47 PC51 |
| 2 | 55.B0701.S21G | 78.22612.51L | CHIP CAP C 22U 25V M0805 X5R | R2_SA;HF_SA;G_SA; | Released | MURATA;SANSUNG;DARFON;TDK | GRM21BR61E226ME44L;CL21A226MAQNNNE;C2012X5R226MFP;C2012X5R1E226MT | Multiple |  | Purchase | SMT | 15 | PCS | C318 C319 C320 C321 PC102 PC182 PC184 PC186 PC187 PC81 PC84 PC85 PC91 PC92 PC94 |
| 2 | 55.B0701.S21G | 78.22623.52L | CHIP CAP C 22U 10V K1206 X5R | R2_SA;HF_SA;G_SA; | Released | MURATA ; SAMSUNG;HOLYSTONE;TDK | GRM31CR61A226KE19L ; CL31A226KPHNNNE;C1206B226K010T;C3216X5R1A226KT | Multiple |  | Purchase | SMT | 1 | PCS | PC19 |
| 2 | 55.B0701.S21G | 78.27044.1FL | CHIP CAP C 27P 50V G0402 NPO | R2_SA;HF_SA;G_SA; | Released | DARFON ; PHYCOMP ; YAGEO ; WALSIN | C1005NP0270GGT ; 223886914279 ; CC0402GRNPO9BN270 ; 0402N270G500CT | Multiple |  | Purchase | SMT | 2 | PCS | C65 C66 |
| 2 | 55.B0701.S21G | 78.33124.2FL | CHIP CAP C 330P 50V K0402 X7R | R2_SA;HF_SA;G_SA; | Released | MURATA;AVX;TDK;TAIYO;PHYCOMN | GRM155R71H331KA01D;04025C331KAT2A;C1005X7R1H331KT000F;UMK105BJ331KV-F;223858715616 | Multiple |  | Purchase | SMT | 1 | PCS | PC191 |
| 2 | 55.B0701.S21G | 78.33224.2BL | CHIP CAP C 3300P 50V K0603 X7R | R2_SA;HF_SA;G_SA; | Released | PHYCOMP;MURATA;AVX;SAMSUNG;DARFON | 223858615629;GRM188R71H332KA01D-50v;06035C332KAT2A;CL10B332KB8NNNC;C1608X7R332KGT | Multiple |  | Purchase | SMT | 1 | PCS | PC69 |
| 2 | 55.B0701.S21G | 78.33420.5FL | CHIP CAP C 0.33U 6.3V K0402 X5 | R2_SA;HF_SA;G_SA; | Released | MURATA;TDK | GRM155R60J334KE01D;C1005X5R0J334KT000F | Multiple |  | Purchase | SMT | 2 | PCS | PC189 PC68 |
| 2 | 55.B0701.S21G | 78.47124.2FL | CHIP CAP C 470P50V K0402 X7R | R2_SA;HF_SA;G_SA; | Released | AVX;DARFON;MURATA;PHYCOMP;TAIYO;TDK;SAMSUNG;WALSIN;YAGEO | 04025C471KAT2A;C1005X7R471KGT;GRM155R71H471KA01D;223858715618;UMK105BJ471KV-F;C1005X7R1H471KT000F;CL05B471KB5NNNC;0402B471K500CT;CC0402KRX7R9BB471 | Multiple |  | Purchase | SMT | 4 | PCS | PC132 PC194 PC2 PC76 |
| 2 | 55.B0701.S21G | 78.47224.2FL | CHIP CAP C 4700P 50V K0402 X7 | R2_SA;HF_SA;G_SA; | Released | MURATA;AVX;TDK;TAYIO;PHYCOMN;DARFON | GRM155R71H472KA01D;04025C472KAT2A;C1005X7R1H472KT000F;UMK105BJ472KV-F;223858715632;C1005X7R472KGT | Multiple |  | Purchase | SMT | 2 | PCS | PC148 PC67 |
| 2 | 55.B0701.S21G | 78.47322.2FL | CHIP CAP C 0.047U 25V K0402 X7 | R2_SA;HF_SA;G_SA; | Released | MURATA;TDK;DARFON;PHYCOMP;WALSIN | GRM155R71E473KA88D;C1005X7R1E473KT000F;C1005X7R473KFT;223891715645;0402B473K250CT | Multiple |  | Purchase | SMT | 4 | PCS | C312 C313 C315 C316 |
| 2 | 55.B0701.S21G | 78.47523.5BL | CHIP CAP C 4.7U 10V K0603 X5R | R2_SA;HF_SA;G_SA; | Released | MURATA;TAIYO;MATSUKI;DARFON;SAMSUNG;PHYCOMP;TDK;WALSIN;AVX | GRM188R61A475KE15D;LMK107BJ475KA-T;MAG03X5R1A475K;C1608X5R475KDT;CL10A475KP8NNNC;223824613672C1608X5R1A475KT000N;0603X475K100CT;CV105X5R475K10AT | Multiple |  | Purchase | SMT | 3 | PCS | PC212 PC40 PC41 |
| 2 | 55.B0701.S21G | 78.47610.51L | CHIP CAP C 47U 6.3V M0805 X5R | R2_SA;HF_SA;G_SA; | Released | TAIYO;SAMSUNG;MURATA;TDK | JMK212BJ476MG-T;CL21A476MQYNNNE;GRM21BR60J476ME15;C2012X5R0J476MT00HE | Multiple |  | Purchase | SMT | 31 | PCS | C359 C360 C361 C362 C363 C364 C365 C366 C367 C368 C369 C370 C371 C372 C373 C374 PC135 PC136 PC144 PC145 PC27 PC28 PC29 PC30 PC31 PC37 PC38 PC39 PC59 PC60 PC7 |
| 2 | 55.B0701.S21G | 78.47611.53L | CHIP CAP C 47U 16V M1210 X5R | R2_SA;HF_SA;G_SA; | Released | MURATA;TAIYO;TAIYO | GRM32ER61C476ME15L;EMK325BJ476MM-T;EMK325BJ476MM-P | Multiple |  | Purchase | SMT | 3 | PCS | PC12 PC183 PC6 |
| 2 | 55.B0701.S21G | 78.5R074.1FL | CHIP CAP C 5P 50V C0402 NPO | R2_SA;HF_SA;G_SA; | Released | AVX;MURATA;PHYCOMP;TAIYO;DARFON;MURATA;WALSIN;SAMSUNG;YAGEO | CM05CG5R0C50AH;GRM1555C1H5R0CZ01D;223886914508;UMK105CG050CW-F;C1005NP0509CGT;GRM1555C1H5R0CA01D;0402N5R0C500LT;CL05C050CB5NNNC;CC0402CRNPO9BN5R0 | Multiple |  | Purchase | SMT | 2 | PCS | PC104 PC126 |
| 2 | 55.B0701.S21G | 78.68034.1FL | CHIP CAP 68P 50V J 0402 NPO | R2_SA;HF_SA;G_SA; | Released | MURATA;TDK;PHYCOMP;TAIYO;;DARFON;SAMSUNG;AVX;MURATA;WALSIN | GRM1555C1H680JZ01D;C1005C0G1H680JT;223886915689;UMK105CH680JW-F;C1005NP0680JGT;CL05C680JB5NNNC;CM05CG680J50AH;GRM1555C1H680JA01D;0402N680J500CT | Multiple |  | Purchase | SMT | 1 | PCS | PC105 |
| 2 | 55.B0701.S21G | 78.68124.2FL | CHIP CAP C 680P 50V K0402 X7R | R2_SA;HF_SA;G_SA; | Released | AVX;DARFON;MURATA;PHYCOMP;TAIYO;TDK;WALSIN | CM05X7R681K50AT;C1005X7R681KGT;GRM155R71H681KA01D;223858715621;UMK105BJ681KV-F;C1005X7R1H681KT;0402B681K500CT | Multiple |  | Purchase | SMT | 2 | PCS | PC101 PC121 |
| 2 | 55.B0701.S21G | 78.68321.2FL | CHIP CAP C 0.068U 16V K0402 X7 | R2_SA;HF_SA;G_SA; | Released | MURATA;TDK;PHYCOMN;DARFON;SAMSUNG | GRM155R71C683KA88D;C1005X7R1C683KT000F;223878715647;C1005X7R683KET;CL05B683K05NNNC | Multiple |  | Purchase | SMT | 1 | PCS | PC15 |
| 2 | 55.B0701.S21G | 78.6R074.1FL | CHIP CAP C 6P 50V C0402 NPO | R2_SA;HF_SA;G_SA; | Released | DARFON;MURATA;PHYCOMP;MURATA | C1005NP0609CGT;GRM1555C1H6R0CZ01D;223886914608;GRM1555C1H6R0CA01D | Multiple |  | Purchase | SMT | 2 | PCS | C26 C33 |
| 2 | 55.B0701.S21G | 79.47719.2BL | CHIP CAP 470UF 2V EEFSX0D471X | R2_SA;HF_SA;G_SA; | Released | PANASONIC | EEFSX0D471XE | Single |  | Purchase | SMT | 5 | PCS | PTC1 PTC2 PTC3 PTC4 PTC5 |
| 2 | 55.B0701.S21G | 82.30001.931 | XTAL 32.768KHZ 8P20PPM DST310S | R2_SA; | Released | KDS | 1TJF080DP1A000A | Single |  | Purchase | SMT | 1 | PCS | X1 |
| 2 | 55.B0701.S21G | 82.30005.A81 | XTAL 14.31818M 20P30PPM 5*3.2 | R2_SA; | Released | TXC | 7A14300038 | Single |  | Purchase | SMT | 1 | PCS | X2 |
| 2 | 55.B0701.S21G | 83.00190.V70 | LED 1.6*0.8 BLUE LTST-C190TBKT | R2_SA;G_SA; | Released | LITEON | LTST-C190TBKT | Single |  | Purchase | SMT | 1 | PCS | LED1 |
| 2 | 55.B0701.S21G | 83.01921.C70 | LED 1.6*0.8 YEL 19-21UYOC/S530 | R2_SA;HF_SA;G_SA; | Released | EVERLIGHT | 19-21UYOC/S530-A2TR8 | Single |  | Purchase | SMT | 1 | PCS | LED14 |
| 2 | 55.B0701.S21G | 83.01921.S70 | LED Y/G 19-21/G6C-BM2P1B/3T SM | R2_SA;HF_SA;G_SA; | Released | EVERLIGHT | 19-21/G6C-BM2P1B/3T | Single |  | Purchase | SMT | 14 | PCS | LED10 LED11 LED12 LED15 LED16 LED17 LED2 LED3 LED4 LED5 LED6 LED7 LED8 LED9 |
| 2 | 55.B0701.S21G | 83.5R603.E3F | DIODE ZEN 5.6V MM3Z5V6T1G SOD | R2_SA;HF_SA; | Released | ON | MM3Z5V6T1G | Single |  | Purchase | SMT | 2 | PCS | PD1 PD2 |
| 2 | 55.B0701.S21G | 84.00359.C31 | FET MOS FDN359BN NC SUPERSOT23 | R2_SA; | Released | FAIRCHILD | FDN359BN | Single |  | Purchase | SMT | 2 | PCS | Q3 Q8 |
| 2 | 55.B0701.S21G | 84.04406.B37 | FET MOS AO4406AL NC SO-8(HF) | R2_SA;HF_SA;G_SA; | Released | AOS | AO4406AL | Single |  | Purchase | SMT | 1 | PCS | Q4 |
| 2 | 55.B0701.S21G | 84.08200.037 | FET MOS FDMC8200 NC POWER33 | R2_SA;HF_SA;G_SA; | Released | FAIRCHILD | FDMC8200 | Single |  | Purchase | SMT | 1 | PCS | PQ1 |
| 2 | 55.B0701.S21G | 84.27002.C3F | FET MOS 2N7002DW-7-F NC SOT363 | R2_SA;HF_SA; | Released | DIODES | 2N7002DW-7-F | Single |  | Purchase | SMT | 9 | PCS | U11 U24 U25 U29 U3 U30 U34 U8 U9 |
| 2 | 55.B0701.S21G | 84.2N702.E31 | FET MOS 2N7002A-7 NC SOT-23 ESD 1.2KV | R2_SA;HF_SA;G_SA; | Released | DIODES | 2N7002A-7 | Single |  | Purchase | SMT | 10 | PCS | Q10 Q13 Q14 Q15 Q16 Q17 Q18 Q5 Q6 Q9 |
| 2 | 55.B0701.S21G | 84.M3904.01K | XTOR MMBT3904TT1G NPN SOT-416 | R2_SA; | Released | ON | MMBT3904TT1G | Single |  | Purchase | SMT | 7 | PCS | PQ2 PQ3 Q1 Q11 Q12 Q2 Q7 |
| 1 | 55.B0701.D21G | 72.25Q64.F01 | IC FALSH MEM W25Q64FVSSIG 8P 8M-BYTE | R2_SA;HF_SA; | Released | WINBOND | W25Q64FVSSIG | Single |  | Purchase | DIP | 1 | PCS | U18 |
